FILE_TYPE = MACRO_DRAWING;
SET COLOR_WIRE YELLOW;
SET COLOR_PROP ORANGE;
SET COLOR_DOT WHITE;
SET COLOR_ARC YELLOW;
SET COLOR_BODY GREEN;
SET COLOR_NOTE PURPLE;
SET PROP_DISPLAY VALUE;
SET PAGE_NUMBER P438;
FORCEADD PT5161LRS..6
(-7575 4475);
FORCEPROP 1 LAST LOCATION U6014
J 0
(-7925 6100);
DISPLAY 0.723404 (-7925 6100);
PAINT GREEN (-7925 6100);
FORCEPROP 0 LAST $SEC 6
J 0
(-7925 6250);
DISPLAY 0.680851 (-7925 6250);
PAINT MONO (-7925 6250);
DISPLAY INVISIBLE (-7925 6250);
FORCEPROP 0 LAST CDS_SEC 6
J 0
(-7925 6250);
DISPLAY 0.680851 (-7925 6250);
DISPLAY INVISIBLE (-7925 6250);
FORCEPROP 0 LASTPIN (-7125 5625) $PN P29
J 0
(-7115 5635);
DISPLAY 0.680851 (-7115 5635);
PAINT MONO (-7115 5635);
FORCEPROP 0 LASTPIN (-7125 5275) $PN AA29
J 0
(-7115 5285);
DISPLAY 0.680851 (-7115 5285);
PAINT MONO (-7115 5285);
FORCEPROP 0 LASTPIN (-7125 4925) $PN AH29
J 0
(-7115 4935);
DISPLAY 0.680851 (-7115 4935);
PAINT MONO (-7115 4935);
FORCEPROP 0 LASTPIN (-7125 4575) $PN AR29
J 0
(-7115 4585);
DISPLAY 0.680851 (-7115 4585);
PAINT MONO (-7115 4585);
FORCEPROP 0 LASTPIN (-7125 4225) $PN BB29
J 0
(-7115 4235);
DISPLAY 0.680851 (-7115 4235);
PAINT MONO (-7115 4235);
FORCEPROP 0 LASTPIN (-7125 3875) $PN BJ29
J 0
(-7115 3885);
DISPLAY 0.680851 (-7115 3885);
PAINT MONO (-7115 3885);
FORCEPROP 0 LASTPIN (-7125 3525) $PN BT29
J 0
(-7115 3535);
DISPLAY 0.680851 (-7115 3535);
PAINT MONO (-7115 3535);
FORCEPROP 0 LASTPIN (-7125 3175) $PN CC29
J 0
(-7115 3185);
DISPLAY 0.680851 (-7115 3185);
PAINT MONO (-7115 3185);
FORCEPROP 0 LASTPIN (-7125 5725) $PN M26
J 0
(-7115 5735);
DISPLAY 0.680851 (-7115 5735);
PAINT MONO (-7115 5735);
FORCEPROP 0 LASTPIN (-7125 5375) $PN W26
J 0
(-7115 5385);
DISPLAY 0.680851 (-7115 5385);
PAINT MONO (-7115 5385);
FORCEPROP 0 LASTPIN (-7125 5025) $PN AF26
J 0
(-7115 5035);
DISPLAY 0.680851 (-7115 5035);
PAINT MONO (-7115 5035);
FORCEPROP 0 LASTPIN (-7125 4675) $PN AN26
J 0
(-7115 4685);
DISPLAY 0.680851 (-7115 4685);
PAINT MONO (-7115 4685);
FORCEPROP 0 LASTPIN (-7125 4325) $PN AY26
J 0
(-7115 4335);
DISPLAY 0.680851 (-7115 4335);
PAINT MONO (-7115 4335);
FORCEPROP 0 LASTPIN (-7125 3975) $PN BG26
J 0
(-7115 3985);
DISPLAY 0.680851 (-7115 3985);
PAINT MONO (-7115 3985);
FORCEPROP 0 LASTPIN (-7125 3625) $PN BP26
J 0
(-7115 3635);
DISPLAY 0.680851 (-7115 3635);
PAINT MONO (-7115 3635);
FORCEPROP 0 LASTPIN (-7125 3275) $PN CA26
J 0
(-7115 3285);
DISPLAY 0.680851 (-7115 3285);
PAINT MONO (-7115 3285);
FORCEPROP 2 LAST PART_TYPE SMLF
J 0
(-7925 6200);
DISPLAY 0.680851 (-7925 6200);
FORCEPROP 1 LAST MATERIAL IC
J 0
(-7925 5950);
DISPLAY 0.723404 (-7925 5950);
PAINT GREEN (-7925 5950);
FORCEPROP 2 LAST VALUE PT5161LRS
J 0
(-7925 6150);
DISPLAY 0.680851 (-7925 6150);
FORCEPROP 1 LAST NEEDS_NO_SIZE TRUE
J 0
(-7575 4475);
DISPLAY 0.723404 (-7575 4475);
PAINT GREEN (-7575 4475);
DISPLAY INVISIBLE (-7575 4475);
FORCEPROP 1 LAST CDS_LMAN_SYM_OUTLINE -350,1450,300,-1400
J 0
(-7575 4475);
DISPLAY 0.468085 (-7575 4475);
PAINT GREEN (-7575 4475);
DISPLAY INVISIBLE (-7575 4475);
FORCEPROP 2 LAST CDS_LIB pure_quanta
J 0
(-7575 4475);
DISPLAY INVISIBLE (-7575 4475);
FORCEPROP 1 LAST PATH I1
J 0
(-7575 4475);
DISPLAY 0.723404 (-7575 4475);
PAINT GREEN (-7575 4475);
DISPLAY INVISIBLE (-7575 4475);
FORCEPROP 1 LAST PART_NUMBER AJ051610U03
J 0
(-7925 6025);
DISPLAY 0.723404 (-7925 6025);
PAINT GREEN (-7925 6025);
DISPLAY INVISIBLE (-7925 6025);
FORCEADD TAP..1
(-6550 4675);
FORCEPROP 3 LASTPIN (-6600 4675) SIG_NAME P5E_CPU1_P0_RX_DP<12>
J 0
(-6590 4685);
DISPLAY 0.659574 (-6590 4685);
PAINT MONO (-6590 4685);
DISPLAY INVISIBLE (-6590 4685);
FORCEPROP 1 LASTPIN (-6600 4675) BN 12
J 0
(-6612 4683);
DISPLAY 0.680851 (-6612 4683);
PAINT GREEN (-6612 4683);
FORCEPROP 2 LAST CDS_LIB standard
J 0
(-6550 4675);
DISPLAY INVISIBLE (-6550 4675);
FORCEPROP 1 LAST BODY_TYPE PLUMBING
J 0
(-6550 4725);
DISPLAY 0.872340 (-6550 4725);
PAINT GREEN (-6550 4725);
DISPLAY INVISIBLE (-6550 4725);
FORCEPROP 1 LAST HDL_TAP TRUE
J 0
(-6225 4550);
DISPLAY 0.872340 (-6225 4550);
DISPLAY INVISIBLE (-6225 4550);
FORCEPROP 1 LAST PATH I10
J 0
(-6552 4675);
DISPLAY 0.872340 (-6552 4675);
PAINT GREEN (-6552 4675);
DISPLAY INVISIBLE (-6552 4675);
FORCEADD TAP..1
(-6350 4575);
FORCEPROP 3 LASTPIN (-6400 4575) SIG_NAME P5E_CPU1_P0_RX_DN<12>
J 0
(-6390 4585);
DISPLAY 0.659574 (-6390 4585);
PAINT MONO (-6390 4585);
DISPLAY INVISIBLE (-6390 4585);
FORCEPROP 1 LASTPIN (-6400 4575) BN 12
J 0
(-6412 4583);
DISPLAY 0.680851 (-6412 4583);
PAINT GREEN (-6412 4583);
FORCEPROP 2 LAST CDS_LIB standard
J 0
(-6350 4575);
DISPLAY INVISIBLE (-6350 4575);
FORCEPROP 1 LAST BODY_TYPE PLUMBING
J 0
(-6350 4625);
DISPLAY 0.872340 (-6350 4625);
PAINT GREEN (-6350 4625);
DISPLAY INVISIBLE (-6350 4625);
FORCEPROP 1 LAST HDL_TAP TRUE
J 0
(-6025 4450);
DISPLAY 0.872340 (-6025 4450);
DISPLAY INVISIBLE (-6025 4450);
FORCEPROP 1 LAST PATH I11
J 0
(-6352 4575);
DISPLAY 0.872340 (-6352 4575);
PAINT GREEN (-6352 4575);
DISPLAY INVISIBLE (-6352 4575);
FORCEADD TAP..1
(-6550 5025);
FORCEPROP 3 LASTPIN (-6600 5025) SIG_NAME P5E_CPU1_P0_RX_DP<13>
J 0
(-6590 5035);
DISPLAY 0.659574 (-6590 5035);
PAINT MONO (-6590 5035);
DISPLAY INVISIBLE (-6590 5035);
FORCEPROP 1 LASTPIN (-6600 5025) BN 13
J 0
(-6612 5033);
DISPLAY 0.680851 (-6612 5033);
PAINT GREEN (-6612 5033);
FORCEPROP 2 LAST CDS_LIB standard
J 0
(-6550 5025);
DISPLAY INVISIBLE (-6550 5025);
FORCEPROP 1 LAST BODY_TYPE PLUMBING
J 0
(-6550 5075);
DISPLAY 0.872340 (-6550 5075);
PAINT GREEN (-6550 5075);
DISPLAY INVISIBLE (-6550 5075);
FORCEPROP 1 LAST HDL_TAP TRUE
J 0
(-6225 4900);
DISPLAY 0.872340 (-6225 4900);
DISPLAY INVISIBLE (-6225 4900);
FORCEPROP 1 LAST PATH I12
J 0
(-6552 5025);
DISPLAY 0.872340 (-6552 5025);
PAINT GREEN (-6552 5025);
DISPLAY INVISIBLE (-6552 5025);
FORCEADD TAP..1
(-6550 5375);
FORCEPROP 3 LASTPIN (-6600 5375) SIG_NAME P5E_CPU1_P0_RX_DP<14>
J 0
(-6590 5385);
DISPLAY 0.659574 (-6590 5385);
PAINT MONO (-6590 5385);
DISPLAY INVISIBLE (-6590 5385);
FORCEPROP 1 LASTPIN (-6600 5375) BN 14
J 0
(-6612 5383);
DISPLAY 0.680851 (-6612 5383);
PAINT GREEN (-6612 5383);
FORCEPROP 2 LAST CDS_LIB standard
J 0
(-6550 5375);
DISPLAY INVISIBLE (-6550 5375);
FORCEPROP 1 LAST BODY_TYPE PLUMBING
J 0
(-6550 5425);
DISPLAY 0.872340 (-6550 5425);
PAINT GREEN (-6550 5425);
DISPLAY INVISIBLE (-6550 5425);
FORCEPROP 1 LAST HDL_TAP TRUE
J 0
(-6225 5250);
DISPLAY 0.872340 (-6225 5250);
DISPLAY INVISIBLE (-6225 5250);
FORCEPROP 1 LAST PATH I13
J 0
(-6552 5375);
DISPLAY 0.872340 (-6552 5375);
PAINT GREEN (-6552 5375);
DISPLAY INVISIBLE (-6552 5375);
FORCEADD TAP..1
(-6350 4925);
FORCEPROP 3 LASTPIN (-6400 4925) SIG_NAME P5E_CPU1_P0_RX_DN<13>
J 0
(-6390 4935);
DISPLAY 0.659574 (-6390 4935);
PAINT MONO (-6390 4935);
DISPLAY INVISIBLE (-6390 4935);
FORCEPROP 1 LASTPIN (-6400 4925) BN 13
J 0
(-6412 4933);
DISPLAY 0.680851 (-6412 4933);
PAINT GREEN (-6412 4933);
FORCEPROP 2 LAST CDS_LIB standard
J 0
(-6350 4925);
DISPLAY INVISIBLE (-6350 4925);
FORCEPROP 1 LAST BODY_TYPE PLUMBING
J 0
(-6350 4975);
DISPLAY 0.872340 (-6350 4975);
PAINT GREEN (-6350 4975);
DISPLAY INVISIBLE (-6350 4975);
FORCEPROP 1 LAST HDL_TAP TRUE
J 0
(-6025 4800);
DISPLAY 0.872340 (-6025 4800);
DISPLAY INVISIBLE (-6025 4800);
FORCEPROP 1 LAST PATH I14
J 0
(-6352 4925);
DISPLAY 0.872340 (-6352 4925);
PAINT GREEN (-6352 4925);
DISPLAY INVISIBLE (-6352 4925);
FORCEADD TAP..1
(-6350 5275);
FORCEPROP 3 LASTPIN (-6400 5275) SIG_NAME P5E_CPU1_P0_RX_DN<14>
J 0
(-6390 5285);
DISPLAY 0.659574 (-6390 5285);
PAINT MONO (-6390 5285);
DISPLAY INVISIBLE (-6390 5285);
FORCEPROP 1 LASTPIN (-6400 5275) BN 14
J 0
(-6412 5283);
DISPLAY 0.680851 (-6412 5283);
PAINT GREEN (-6412 5283);
FORCEPROP 2 LAST CDS_LIB standard
J 0
(-6350 5275);
DISPLAY INVISIBLE (-6350 5275);
FORCEPROP 1 LAST BODY_TYPE PLUMBING
J 0
(-6350 5325);
DISPLAY 0.872340 (-6350 5325);
PAINT GREEN (-6350 5325);
DISPLAY INVISIBLE (-6350 5325);
FORCEPROP 1 LAST HDL_TAP TRUE
J 0
(-6025 5150);
DISPLAY 0.872340 (-6025 5150);
DISPLAY INVISIBLE (-6025 5150);
FORCEPROP 1 LAST PATH I15
J 0
(-6352 5275);
DISPLAY 0.872340 (-6352 5275);
PAINT GREEN (-6352 5275);
DISPLAY INVISIBLE (-6352 5275);
FORCEADD TAP..1
(-6550 5725);
FORCEPROP 3 LASTPIN (-6600 5725) SIG_NAME P5E_CPU1_P0_RX_DP<15>
J 0
(-6590 5735);
DISPLAY 0.659574 (-6590 5735);
PAINT MONO (-6590 5735);
DISPLAY INVISIBLE (-6590 5735);
FORCEPROP 1 LASTPIN (-6600 5725) BN 15
J 0
(-6612 5733);
DISPLAY 0.680851 (-6612 5733);
PAINT GREEN (-6612 5733);
FORCEPROP 2 LAST CDS_LIB standard
J 0
(-6550 5725);
DISPLAY INVISIBLE (-6550 5725);
FORCEPROP 1 LAST BODY_TYPE PLUMBING
J 0
(-6550 5775);
DISPLAY 0.872340 (-6550 5775);
PAINT GREEN (-6550 5775);
DISPLAY INVISIBLE (-6550 5775);
FORCEPROP 1 LAST HDL_TAP TRUE
J 0
(-6225 5600);
DISPLAY 0.872340 (-6225 5600);
DISPLAY INVISIBLE (-6225 5600);
FORCEPROP 1 LAST PATH I16
J 0
(-6552 5725);
DISPLAY 0.872340 (-6552 5725);
PAINT GREEN (-6552 5725);
DISPLAY INVISIBLE (-6552 5725);
FORCEADD TAP..1
(-6350 5625);
FORCEPROP 3 LASTPIN (-6400 5625) SIG_NAME P5E_CPU1_P0_RX_DN<15>
J 0
(-6390 5635);
DISPLAY 0.659574 (-6390 5635);
PAINT MONO (-6390 5635);
DISPLAY INVISIBLE (-6390 5635);
FORCEPROP 1 LASTPIN (-6400 5625) BN 15
J 0
(-6412 5633);
DISPLAY 0.680851 (-6412 5633);
PAINT GREEN (-6412 5633);
FORCEPROP 2 LAST CDS_LIB standard
J 0
(-6350 5625);
DISPLAY INVISIBLE (-6350 5625);
FORCEPROP 1 LAST BODY_TYPE PLUMBING
J 0
(-6350 5675);
DISPLAY 0.872340 (-6350 5675);
PAINT GREEN (-6350 5675);
DISPLAY INVISIBLE (-6350 5675);
FORCEPROP 1 LAST HDL_TAP TRUE
J 0
(-6025 5500);
DISPLAY 0.872340 (-6025 5500);
DISPLAY INVISIBLE (-6025 5500);
FORCEPROP 1 LAST PATH I17
J 0
(-6352 5625);
DISPLAY 0.872340 (-6352 5625);
PAINT GREEN (-6352 5625);
DISPLAY INVISIBLE (-6352 5625);
FORCEADD OFFPAGE..5
R 2
(-5350 5700);
FORCEPROP 2 LAST $XR0 51 
J 0
(-5161 5700);
DISPLAY 0.638298 (-5161 5700);
PAINT MONO (-5161 5700);
FORCEPROP 2 LAST CDS_LIB standard
J 0
(-5350 5700);
DISPLAY INVISIBLE (-5350 5700);
FORCEPROP 1 LAST OFFPAGE TRUE
J 2
(-5675 5575);
DISPLAY 0.872340 (-5675 5575);
PAINT GREEN (-5675 5575);
DISPLAY INVISIBLE (-5675 5575);
FORCEPROP 1 LAST COMMENT_BODY TRUE
J 2
(-5450 5625);
DISPLAY 0.872340 (-5450 5625);
PAINT GREEN (-5450 5625);
DISPLAY INVISIBLE (-5450 5625);
FORCEPROP 2 LAST PATH I18
J 0
(-5175 5775);
DISPLAY 0.680851 (-5175 5775);
DISPLAY INVISIBLE (-5175 5775);
FORCEADD OFFPAGE..5
R 2
(-5325 5825);
FORCEPROP 2 LAST $XR0 51 
J 0
(-5136 5825);
DISPLAY 0.638298 (-5136 5825);
PAINT MONO (-5136 5825);
FORCEPROP 2 LAST CDS_LIB standard
J 0
(-5325 5825);
DISPLAY INVISIBLE (-5325 5825);
FORCEPROP 1 LAST OFFPAGE TRUE
J 2
(-5650 5700);
DISPLAY 0.872340 (-5650 5700);
PAINT GREEN (-5650 5700);
DISPLAY INVISIBLE (-5650 5700);
FORCEPROP 1 LAST COMMENT_BODY TRUE
J 2
(-5425 5750);
DISPLAY 0.872340 (-5425 5750);
PAINT GREEN (-5425 5750);
DISPLAY INVISIBLE (-5425 5750);
FORCEPROP 2 LAST PATH I19
J 0
(-5150 5900);
DISPLAY 0.680851 (-5150 5900);
DISPLAY INVISIBLE (-5150 5900);
FORCEADD TAP..1
(-6550 3275);
FORCEPROP 3 LASTPIN (-6600 3275) SIG_NAME P5E_CPU1_P0_RX_DP<8>
J 0
(-6590 3285);
DISPLAY 0.659574 (-6590 3285);
PAINT MONO (-6590 3285);
DISPLAY INVISIBLE (-6590 3285);
FORCEPROP 1 LASTPIN (-6600 3275) BN 8
J 0
(-6612 3283);
DISPLAY 0.680851 (-6612 3283);
PAINT GREEN (-6612 3283);
FORCEPROP 2 LAST CDS_LIB standard
J 0
(-6550 3275);
DISPLAY INVISIBLE (-6550 3275);
FORCEPROP 1 LAST BODY_TYPE PLUMBING
J 0
(-6550 3325);
DISPLAY 0.872340 (-6550 3325);
PAINT GREEN (-6550 3325);
DISPLAY INVISIBLE (-6550 3325);
FORCEPROP 1 LAST HDL_TAP TRUE
J 0
(-6225 3150);
DISPLAY 0.872340 (-6225 3150);
DISPLAY INVISIBLE (-6225 3150);
FORCEPROP 1 LAST PATH I2
J 0
(-6552 3275);
DISPLAY 0.872340 (-6552 3275);
PAINT GREEN (-6552 3275);
DISPLAY INVISIBLE (-6552 3275);
FORCEADD TAP..1
(-2025 3350);
FORCEPROP 3 LASTPIN (-2075 3350) SIG_NAME P5E_CPU1_P0_RX_DP<0>
J 0
(-2065 3360);
DISPLAY 0.659574 (-2065 3360);
PAINT MONO (-2065 3360);
DISPLAY INVISIBLE (-2065 3360);
FORCEPROP 1 LASTPIN (-2075 3350) BN 0
J 0
(-2087 3358);
DISPLAY 0.680851 (-2087 3358);
PAINT GREEN (-2087 3358);
FORCEPROP 2 LAST CDS_LIB standard
J 0
(-2025 3350);
DISPLAY INVISIBLE (-2025 3350);
FORCEPROP 1 LAST BODY_TYPE PLUMBING
J 0
(-2025 3400);
DISPLAY 0.872340 (-2025 3400);
PAINT GREEN (-2025 3400);
DISPLAY INVISIBLE (-2025 3400);
FORCEPROP 1 LAST HDL_TAP TRUE
J 0
(-1700 3225);
DISPLAY 0.872340 (-1700 3225);
DISPLAY INVISIBLE (-1700 3225);
FORCEPROP 1 LAST PATH I20
J 0
(-2027 3350);
DISPLAY 0.872340 (-2027 3350);
PAINT GREEN (-2027 3350);
DISPLAY INVISIBLE (-2027 3350);
FORCEADD TAP..1
(-1825 3250);
FORCEPROP 3 LASTPIN (-1875 3250) SIG_NAME P5E_CPU1_P0_RX_DN<0>
J 0
(-1865 3260);
DISPLAY 0.659574 (-1865 3260);
PAINT MONO (-1865 3260);
DISPLAY INVISIBLE (-1865 3260);
FORCEPROP 1 LASTPIN (-1875 3250) BN 0
J 0
(-1887 3258);
DISPLAY 0.680851 (-1887 3258);
PAINT GREEN (-1887 3258);
FORCEPROP 2 LAST CDS_LIB standard
J 0
(-1825 3250);
DISPLAY INVISIBLE (-1825 3250);
FORCEPROP 1 LAST BODY_TYPE PLUMBING
J 0
(-1825 3300);
DISPLAY 0.872340 (-1825 3300);
PAINT GREEN (-1825 3300);
DISPLAY INVISIBLE (-1825 3300);
FORCEPROP 1 LAST HDL_TAP TRUE
J 0
(-1500 3125);
DISPLAY 0.872340 (-1500 3125);
DISPLAY INVISIBLE (-1500 3125);
FORCEPROP 1 LAST PATH I21
J 0
(-1827 3250);
DISPLAY 0.872340 (-1827 3250);
PAINT GREEN (-1827 3250);
DISPLAY INVISIBLE (-1827 3250);
FORCEADD TAP..1
(-1825 3600);
FORCEPROP 3 LASTPIN (-1875 3600) SIG_NAME P5E_CPU1_P0_RX_DN<1>
J 0
(-1865 3610);
DISPLAY 0.659574 (-1865 3610);
PAINT MONO (-1865 3610);
DISPLAY INVISIBLE (-1865 3610);
FORCEPROP 1 LASTPIN (-1875 3600) BN 1
J 0
(-1887 3608);
DISPLAY 0.680851 (-1887 3608);
PAINT GREEN (-1887 3608);
FORCEPROP 2 LAST CDS_LIB standard
J 0
(-1825 3600);
DISPLAY INVISIBLE (-1825 3600);
FORCEPROP 1 LAST BODY_TYPE PLUMBING
J 0
(-1825 3650);
DISPLAY 0.872340 (-1825 3650);
PAINT GREEN (-1825 3650);
DISPLAY INVISIBLE (-1825 3650);
FORCEPROP 1 LAST HDL_TAP TRUE
J 0
(-1500 3475);
DISPLAY 0.872340 (-1500 3475);
DISPLAY INVISIBLE (-1500 3475);
FORCEPROP 1 LAST PATH I22
J 0
(-1827 3600);
DISPLAY 0.872340 (-1827 3600);
PAINT GREEN (-1827 3600);
DISPLAY INVISIBLE (-1827 3600);
FORCEADD TAP..1
(-2025 3700);
FORCEPROP 3 LASTPIN (-2075 3700) SIG_NAME P5E_CPU1_P0_RX_DP<1>
J 0
(-2065 3710);
DISPLAY 0.659574 (-2065 3710);
PAINT MONO (-2065 3710);
DISPLAY INVISIBLE (-2065 3710);
FORCEPROP 1 LASTPIN (-2075 3700) BN 1
J 0
(-2087 3708);
DISPLAY 0.680851 (-2087 3708);
PAINT GREEN (-2087 3708);
FORCEPROP 2 LAST CDS_LIB standard
J 0
(-2025 3700);
DISPLAY INVISIBLE (-2025 3700);
FORCEPROP 1 LAST BODY_TYPE PLUMBING
J 0
(-2025 3750);
DISPLAY 0.872340 (-2025 3750);
PAINT GREEN (-2025 3750);
DISPLAY INVISIBLE (-2025 3750);
FORCEPROP 1 LAST HDL_TAP TRUE
J 0
(-1700 3575);
DISPLAY 0.872340 (-1700 3575);
DISPLAY INVISIBLE (-1700 3575);
FORCEPROP 1 LAST PATH I23
J 0
(-2027 3700);
DISPLAY 0.872340 (-2027 3700);
PAINT GREEN (-2027 3700);
DISPLAY INVISIBLE (-2027 3700);
FORCEADD TAP..1
(-2025 4050);
FORCEPROP 3 LASTPIN (-2075 4050) SIG_NAME P5E_CPU1_P0_RX_DP<2>
J 0
(-2065 4060);
DISPLAY 0.659574 (-2065 4060);
PAINT MONO (-2065 4060);
DISPLAY INVISIBLE (-2065 4060);
FORCEPROP 1 LASTPIN (-2075 4050) BN 2
J 0
(-2087 4058);
DISPLAY 0.680851 (-2087 4058);
PAINT GREEN (-2087 4058);
FORCEPROP 2 LAST CDS_LIB standard
J 0
(-2025 4050);
DISPLAY INVISIBLE (-2025 4050);
FORCEPROP 1 LAST BODY_TYPE PLUMBING
J 0
(-2025 4100);
DISPLAY 0.872340 (-2025 4100);
PAINT GREEN (-2025 4100);
DISPLAY INVISIBLE (-2025 4100);
FORCEPROP 1 LAST HDL_TAP TRUE
J 0
(-1700 3925);
DISPLAY 0.872340 (-1700 3925);
DISPLAY INVISIBLE (-1700 3925);
FORCEPROP 1 LAST PATH I24
J 0
(-2027 4050);
DISPLAY 0.872340 (-2027 4050);
PAINT GREEN (-2027 4050);
DISPLAY INVISIBLE (-2027 4050);
FORCEADD TAP..1
(-1825 3950);
FORCEPROP 3 LASTPIN (-1875 3950) SIG_NAME P5E_CPU1_P0_RX_DN<2>
J 0
(-1865 3960);
DISPLAY 0.659574 (-1865 3960);
PAINT MONO (-1865 3960);
DISPLAY INVISIBLE (-1865 3960);
FORCEPROP 1 LASTPIN (-1875 3950) BN 2
J 0
(-1887 3958);
DISPLAY 0.680851 (-1887 3958);
PAINT GREEN (-1887 3958);
FORCEPROP 2 LAST CDS_LIB standard
J 0
(-1825 3950);
DISPLAY INVISIBLE (-1825 3950);
FORCEPROP 1 LAST BODY_TYPE PLUMBING
J 0
(-1825 4000);
DISPLAY 0.872340 (-1825 4000);
PAINT GREEN (-1825 4000);
DISPLAY INVISIBLE (-1825 4000);
FORCEPROP 1 LAST HDL_TAP TRUE
J 0
(-1500 3825);
DISPLAY 0.872340 (-1500 3825);
DISPLAY INVISIBLE (-1500 3825);
FORCEPROP 1 LAST PATH I25
J 0
(-1827 3950);
DISPLAY 0.872340 (-1827 3950);
PAINT GREEN (-1827 3950);
DISPLAY INVISIBLE (-1827 3950);
FORCEADD TAP..1
(-1825 4300);
FORCEPROP 3 LASTPIN (-1875 4300) SIG_NAME P5E_CPU1_P0_RX_DN<3>
J 0
(-1865 4310);
DISPLAY 0.659574 (-1865 4310);
PAINT MONO (-1865 4310);
DISPLAY INVISIBLE (-1865 4310);
FORCEPROP 1 LASTPIN (-1875 4300) BN 3
J 0
(-1887 4308);
DISPLAY 0.680851 (-1887 4308);
PAINT GREEN (-1887 4308);
FORCEPROP 2 LAST CDS_LIB standard
J 0
(-1825 4300);
DISPLAY INVISIBLE (-1825 4300);
FORCEPROP 1 LAST BODY_TYPE PLUMBING
J 0
(-1825 4350);
DISPLAY 0.872340 (-1825 4350);
PAINT GREEN (-1825 4350);
DISPLAY INVISIBLE (-1825 4350);
FORCEPROP 1 LAST HDL_TAP TRUE
J 0
(-1500 4175);
DISPLAY 0.872340 (-1500 4175);
DISPLAY INVISIBLE (-1500 4175);
FORCEPROP 1 LAST PATH I26
J 0
(-1827 4300);
DISPLAY 0.872340 (-1827 4300);
PAINT GREEN (-1827 4300);
DISPLAY INVISIBLE (-1827 4300);
FORCEADD TAP..1
(-1825 4650);
FORCEPROP 3 LASTPIN (-1875 4650) SIG_NAME P5E_CPU1_P0_RX_DN<4>
J 0
(-1865 4660);
DISPLAY 0.659574 (-1865 4660);
PAINT MONO (-1865 4660);
DISPLAY INVISIBLE (-1865 4660);
FORCEPROP 1 LASTPIN (-1875 4650) BN 4
J 0
(-1887 4658);
DISPLAY 0.680851 (-1887 4658);
PAINT GREEN (-1887 4658);
FORCEPROP 2 LAST CDS_LIB standard
J 0
(-1825 4650);
DISPLAY INVISIBLE (-1825 4650);
FORCEPROP 1 LAST BODY_TYPE PLUMBING
J 0
(-1825 4700);
DISPLAY 0.872340 (-1825 4700);
PAINT GREEN (-1825 4700);
DISPLAY INVISIBLE (-1825 4700);
FORCEPROP 1 LAST HDL_TAP TRUE
J 0
(-1500 4525);
DISPLAY 0.872340 (-1500 4525);
DISPLAY INVISIBLE (-1500 4525);
FORCEPROP 1 LAST PATH I27
J 0
(-1827 4650);
DISPLAY 0.872340 (-1827 4650);
PAINT GREEN (-1827 4650);
DISPLAY INVISIBLE (-1827 4650);
FORCEADD TAP..1
(-2025 4400);
FORCEPROP 3 LASTPIN (-2075 4400) SIG_NAME P5E_CPU1_P0_RX_DP<3>
J 0
(-2065 4410);
DISPLAY 0.659574 (-2065 4410);
PAINT MONO (-2065 4410);
DISPLAY INVISIBLE (-2065 4410);
FORCEPROP 1 LASTPIN (-2075 4400) BN 3
J 0
(-2087 4408);
DISPLAY 0.680851 (-2087 4408);
PAINT GREEN (-2087 4408);
FORCEPROP 2 LAST CDS_LIB standard
J 0
(-2025 4400);
DISPLAY INVISIBLE (-2025 4400);
FORCEPROP 1 LAST BODY_TYPE PLUMBING
J 0
(-2025 4450);
DISPLAY 0.872340 (-2025 4450);
PAINT GREEN (-2025 4450);
DISPLAY INVISIBLE (-2025 4450);
FORCEPROP 1 LAST HDL_TAP TRUE
J 0
(-1700 4275);
DISPLAY 0.872340 (-1700 4275);
DISPLAY INVISIBLE (-1700 4275);
FORCEPROP 1 LAST PATH I28
J 0
(-2027 4400);
DISPLAY 0.872340 (-2027 4400);
PAINT GREEN (-2027 4400);
DISPLAY INVISIBLE (-2027 4400);
FORCEADD TAP..1
(-2025 4750);
FORCEPROP 3 LASTPIN (-2075 4750) SIG_NAME P5E_CPU1_P0_RX_DP<4>
J 0
(-2065 4760);
DISPLAY 0.659574 (-2065 4760);
PAINT MONO (-2065 4760);
DISPLAY INVISIBLE (-2065 4760);
FORCEPROP 1 LASTPIN (-2075 4750) BN 4
J 0
(-2087 4758);
DISPLAY 0.680851 (-2087 4758);
PAINT GREEN (-2087 4758);
FORCEPROP 2 LAST CDS_LIB standard
J 0
(-2025 4750);
DISPLAY INVISIBLE (-2025 4750);
FORCEPROP 1 LAST BODY_TYPE PLUMBING
J 0
(-2025 4800);
DISPLAY 0.872340 (-2025 4800);
PAINT GREEN (-2025 4800);
DISPLAY INVISIBLE (-2025 4800);
FORCEPROP 1 LAST HDL_TAP TRUE
J 0
(-1700 4625);
DISPLAY 0.872340 (-1700 4625);
DISPLAY INVISIBLE (-1700 4625);
FORCEPROP 1 LAST PATH I29
J 0
(-2027 4750);
DISPLAY 0.872340 (-2027 4750);
PAINT GREEN (-2027 4750);
DISPLAY INVISIBLE (-2027 4750);
FORCEADD TAP..1
(-6350 3175);
FORCEPROP 3 LASTPIN (-6400 3175) SIG_NAME P5E_CPU1_P0_RX_DN<8>
J 0
(-6390 3185);
DISPLAY 0.659574 (-6390 3185);
PAINT MONO (-6390 3185);
DISPLAY INVISIBLE (-6390 3185);
FORCEPROP 1 LASTPIN (-6400 3175) BN 8
J 0
(-6412 3183);
DISPLAY 0.680851 (-6412 3183);
PAINT GREEN (-6412 3183);
FORCEPROP 2 LAST CDS_LIB standard
J 0
(-6350 3175);
DISPLAY INVISIBLE (-6350 3175);
FORCEPROP 1 LAST BODY_TYPE PLUMBING
J 0
(-6350 3225);
DISPLAY 0.872340 (-6350 3225);
PAINT GREEN (-6350 3225);
DISPLAY INVISIBLE (-6350 3225);
FORCEPROP 1 LAST HDL_TAP TRUE
J 0
(-6025 3050);
DISPLAY 0.872340 (-6025 3050);
DISPLAY INVISIBLE (-6025 3050);
FORCEPROP 1 LAST PATH I3
J 0
(-6352 3175);
DISPLAY 0.872340 (-6352 3175);
PAINT GREEN (-6352 3175);
DISPLAY INVISIBLE (-6352 3175);
FORCEADD TAP..1
(-2025 5100);
FORCEPROP 3 LASTPIN (-2075 5100) SIG_NAME P5E_CPU1_P0_RX_DP<5>
J 0
(-2065 5110);
DISPLAY 0.659574 (-2065 5110);
PAINT MONO (-2065 5110);
DISPLAY INVISIBLE (-2065 5110);
FORCEPROP 1 LASTPIN (-2075 5100) BN 5
J 0
(-2087 5108);
DISPLAY 0.680851 (-2087 5108);
PAINT GREEN (-2087 5108);
FORCEPROP 2 LAST CDS_LIB standard
J 0
(-2025 5100);
DISPLAY INVISIBLE (-2025 5100);
FORCEPROP 1 LAST BODY_TYPE PLUMBING
J 0
(-2025 5150);
DISPLAY 0.872340 (-2025 5150);
PAINT GREEN (-2025 5150);
DISPLAY INVISIBLE (-2025 5150);
FORCEPROP 1 LAST HDL_TAP TRUE
J 0
(-1700 4975);
DISPLAY 0.872340 (-1700 4975);
DISPLAY INVISIBLE (-1700 4975);
FORCEPROP 1 LAST PATH I30
J 0
(-2027 5100);
DISPLAY 0.872340 (-2027 5100);
PAINT GREEN (-2027 5100);
DISPLAY INVISIBLE (-2027 5100);
FORCEADD TAP..1
(-1825 5000);
FORCEPROP 3 LASTPIN (-1875 5000) SIG_NAME P5E_CPU1_P0_RX_DN<5>
J 0
(-1865 5010);
DISPLAY 0.659574 (-1865 5010);
PAINT MONO (-1865 5010);
DISPLAY INVISIBLE (-1865 5010);
FORCEPROP 1 LASTPIN (-1875 5000) BN 5
J 0
(-1887 5008);
DISPLAY 0.680851 (-1887 5008);
PAINT GREEN (-1887 5008);
FORCEPROP 2 LAST CDS_LIB standard
J 0
(-1825 5000);
DISPLAY INVISIBLE (-1825 5000);
FORCEPROP 1 LAST BODY_TYPE PLUMBING
J 0
(-1825 5050);
DISPLAY 0.872340 (-1825 5050);
PAINT GREEN (-1825 5050);
DISPLAY INVISIBLE (-1825 5050);
FORCEPROP 1 LAST HDL_TAP TRUE
J 0
(-1500 4875);
DISPLAY 0.872340 (-1500 4875);
DISPLAY INVISIBLE (-1500 4875);
FORCEPROP 1 LAST PATH I31
J 0
(-1827 5000);
DISPLAY 0.872340 (-1827 5000);
PAINT GREEN (-1827 5000);
DISPLAY INVISIBLE (-1827 5000);
FORCEADD TAP..1
(-1825 5350);
FORCEPROP 3 LASTPIN (-1875 5350) SIG_NAME P5E_CPU1_P0_RX_DN<6>
J 0
(-1865 5360);
DISPLAY 0.659574 (-1865 5360);
PAINT MONO (-1865 5360);
DISPLAY INVISIBLE (-1865 5360);
FORCEPROP 1 LASTPIN (-1875 5350) BN 6
J 0
(-1887 5358);
DISPLAY 0.680851 (-1887 5358);
PAINT GREEN (-1887 5358);
FORCEPROP 2 LAST CDS_LIB standard
J 0
(-1825 5350);
DISPLAY INVISIBLE (-1825 5350);
FORCEPROP 1 LAST BODY_TYPE PLUMBING
J 0
(-1825 5400);
DISPLAY 0.872340 (-1825 5400);
PAINT GREEN (-1825 5400);
DISPLAY INVISIBLE (-1825 5400);
FORCEPROP 1 LAST HDL_TAP TRUE
J 0
(-1500 5225);
DISPLAY 0.872340 (-1500 5225);
DISPLAY INVISIBLE (-1500 5225);
FORCEPROP 1 LAST PATH I32
J 0
(-1827 5350);
DISPLAY 0.872340 (-1827 5350);
PAINT GREEN (-1827 5350);
DISPLAY INVISIBLE (-1827 5350);
FORCEADD TAP..1
(-2025 5450);
FORCEPROP 3 LASTPIN (-2075 5450) SIG_NAME P5E_CPU1_P0_RX_DP<6>
J 0
(-2065 5460);
DISPLAY 0.659574 (-2065 5460);
PAINT MONO (-2065 5460);
DISPLAY INVISIBLE (-2065 5460);
FORCEPROP 1 LASTPIN (-2075 5450) BN 6
J 0
(-2087 5458);
DISPLAY 0.680851 (-2087 5458);
PAINT GREEN (-2087 5458);
FORCEPROP 2 LAST CDS_LIB standard
J 0
(-2025 5450);
DISPLAY INVISIBLE (-2025 5450);
FORCEPROP 1 LAST BODY_TYPE PLUMBING
J 0
(-2025 5500);
DISPLAY 0.872340 (-2025 5500);
PAINT GREEN (-2025 5500);
DISPLAY INVISIBLE (-2025 5500);
FORCEPROP 1 LAST HDL_TAP TRUE
J 0
(-1700 5325);
DISPLAY 0.872340 (-1700 5325);
DISPLAY INVISIBLE (-1700 5325);
FORCEPROP 1 LAST PATH I33
J 0
(-2027 5450);
DISPLAY 0.872340 (-2027 5450);
PAINT GREEN (-2027 5450);
DISPLAY INVISIBLE (-2027 5450);
FORCEADD TAP..1
(-2025 5800);
FORCEPROP 3 LASTPIN (-2075 5800) SIG_NAME P5E_CPU1_P0_RX_DP<7>
J 0
(-2065 5810);
DISPLAY 0.659574 (-2065 5810);
PAINT MONO (-2065 5810);
DISPLAY INVISIBLE (-2065 5810);
FORCEPROP 1 LASTPIN (-2075 5800) BN 7
J 0
(-2087 5808);
DISPLAY 0.680851 (-2087 5808);
PAINT GREEN (-2087 5808);
FORCEPROP 2 LAST CDS_LIB standard
J 0
(-2025 5800);
DISPLAY INVISIBLE (-2025 5800);
FORCEPROP 1 LAST BODY_TYPE PLUMBING
J 0
(-2025 5850);
DISPLAY 0.872340 (-2025 5850);
PAINT GREEN (-2025 5850);
DISPLAY INVISIBLE (-2025 5850);
FORCEPROP 1 LAST HDL_TAP TRUE
J 0
(-1700 5675);
DISPLAY 0.872340 (-1700 5675);
DISPLAY INVISIBLE (-1700 5675);
FORCEPROP 1 LAST PATH I34
J 0
(-2027 5800);
DISPLAY 0.872340 (-2027 5800);
PAINT GREEN (-2027 5800);
DISPLAY INVISIBLE (-2027 5800);
FORCEADD TAP..1
(-1825 5700);
FORCEPROP 3 LASTPIN (-1875 5700) SIG_NAME P5E_CPU1_P0_RX_DN<7>
J 0
(-1865 5710);
DISPLAY 0.659574 (-1865 5710);
PAINT MONO (-1865 5710);
DISPLAY INVISIBLE (-1865 5710);
FORCEPROP 1 LASTPIN (-1875 5700) BN 7
J 0
(-1887 5708);
DISPLAY 0.680851 (-1887 5708);
PAINT GREEN (-1887 5708);
FORCEPROP 2 LAST CDS_LIB standard
J 0
(-1825 5700);
DISPLAY INVISIBLE (-1825 5700);
FORCEPROP 1 LAST BODY_TYPE PLUMBING
J 0
(-1825 5750);
DISPLAY 0.872340 (-1825 5750);
PAINT GREEN (-1825 5750);
DISPLAY INVISIBLE (-1825 5750);
FORCEPROP 1 LAST HDL_TAP TRUE
J 0
(-1500 5575);
DISPLAY 0.872340 (-1500 5575);
DISPLAY INVISIBLE (-1500 5575);
FORCEPROP 1 LAST PATH I35
J 0
(-1827 5700);
DISPLAY 0.872340 (-1827 5700);
PAINT GREEN (-1827 5700);
DISPLAY INVISIBLE (-1827 5700);
FORCEADD OFFPAGE..5
R 2
(-825 5900);
FORCEPROP 2 LAST $XR0 51 
J 0
(-636 5900);
DISPLAY 0.638298 (-636 5900);
PAINT MONO (-636 5900);
FORCEPROP 2 LAST CDS_LIB standard
J 0
(-825 5900);
DISPLAY INVISIBLE (-825 5900);
FORCEPROP 1 LAST OFFPAGE TRUE
J 2
(-1150 5775);
DISPLAY 0.872340 (-1150 5775);
PAINT GREEN (-1150 5775);
DISPLAY INVISIBLE (-1150 5775);
FORCEPROP 1 LAST COMMENT_BODY TRUE
J 2
(-925 5825);
DISPLAY 0.872340 (-925 5825);
PAINT GREEN (-925 5825);
DISPLAY INVISIBLE (-925 5825);
FORCEPROP 2 LAST PATH I36
J 0
(-650 5975);
DISPLAY 0.680851 (-650 5975);
DISPLAY INVISIBLE (-650 5975);
FORCEADD OFFPAGE..5
R 2
(-800 6025);
FORCEPROP 2 LAST $XR0 51 
J 0
(-611 6025);
DISPLAY 0.638298 (-611 6025);
PAINT MONO (-611 6025);
FORCEPROP 2 LAST CDS_LIB standard
J 0
(-800 6025);
DISPLAY INVISIBLE (-800 6025);
FORCEPROP 1 LAST OFFPAGE TRUE
J 2
(-1125 5900);
DISPLAY 0.872340 (-1125 5900);
PAINT GREEN (-1125 5900);
DISPLAY INVISIBLE (-1125 5900);
FORCEPROP 1 LAST COMMENT_BODY TRUE
J 2
(-900 5950);
DISPLAY 0.872340 (-900 5950);
PAINT GREEN (-900 5950);
DISPLAY INVISIBLE (-900 5950);
FORCEPROP 2 LAST PATH I37
J 0
(-625 6100);
DISPLAY 0.680851 (-625 6100);
DISPLAY INVISIBLE (-625 6100);
FORCEADD PT5161LRS..7
(-3050 4550);
FORCEPROP 1 LAST LOCATION U6014
J 0
(-3400 6175);
DISPLAY 0.723404 (-3400 6175);
PAINT GREEN (-3400 6175);
FORCEPROP 0 LAST $SEC 7
J 0
(-3400 6325);
DISPLAY 0.680851 (-3400 6325);
PAINT MONO (-3400 6325);
DISPLAY INVISIBLE (-3400 6325);
FORCEPROP 0 LAST CDS_SEC 7
J 0
(-3400 6325);
DISPLAY 0.680851 (-3400 6325);
DISPLAY INVISIBLE (-3400 6325);
FORCEPROP 0 LASTPIN (-2600 5700) $PN CK29
J 0
(-2590 5710);
DISPLAY 0.680851 (-2590 5710);
PAINT MONO (-2590 5710);
FORCEPROP 0 LASTPIN (-2600 5350) $PN CU29
J 0
(-2590 5360);
DISPLAY 0.680851 (-2590 5360);
PAINT MONO (-2590 5360);
FORCEPROP 0 LASTPIN (-2600 5000) $PN DD29
J 0
(-2590 5010);
DISPLAY 0.680851 (-2590 5010);
PAINT MONO (-2590 5010);
FORCEPROP 0 LASTPIN (-2600 4650) $PN DL29
J 0
(-2590 4660);
DISPLAY 0.680851 (-2590 4660);
PAINT MONO (-2590 4660);
FORCEPROP 0 LASTPIN (-2600 4300) $PN DV29
J 0
(-2590 4310);
DISPLAY 0.680851 (-2590 4310);
PAINT MONO (-2590 4310);
FORCEPROP 0 LASTPIN (-2600 3950) $PN EE29
J 0
(-2590 3960);
DISPLAY 0.680851 (-2590 3960);
PAINT MONO (-2590 3960);
FORCEPROP 0 LASTPIN (-2600 3600) $PN EM29
J 0
(-2590 3610);
DISPLAY 0.680851 (-2590 3610);
PAINT MONO (-2590 3610);
FORCEPROP 0 LASTPIN (-2600 3250) $PN EW29
J 0
(-2590 3260);
DISPLAY 0.680851 (-2590 3260);
PAINT MONO (-2590 3260);
FORCEPROP 0 LASTPIN (-2600 5800) $PN CH26
J 0
(-2590 5810);
DISPLAY 0.680851 (-2590 5810);
PAINT MONO (-2590 5810);
FORCEPROP 0 LASTPIN (-2600 5450) $PN CR26
J 0
(-2590 5460);
DISPLAY 0.680851 (-2590 5460);
PAINT MONO (-2590 5460);
FORCEPROP 0 LASTPIN (-2600 5100) $PN DB26
J 0
(-2590 5110);
DISPLAY 0.680851 (-2590 5110);
PAINT MONO (-2590 5110);
FORCEPROP 0 LASTPIN (-2600 4750) $PN DJ26
J 0
(-2590 4760);
DISPLAY 0.680851 (-2590 4760);
PAINT MONO (-2590 4760);
FORCEPROP 0 LASTPIN (-2600 4400) $PN DT26
J 0
(-2590 4410);
DISPLAY 0.680851 (-2590 4410);
PAINT MONO (-2590 4410);
FORCEPROP 0 LASTPIN (-2600 4050) $PN EC26
J 0
(-2590 4060);
DISPLAY 0.680851 (-2590 4060);
PAINT MONO (-2590 4060);
FORCEPROP 0 LASTPIN (-2600 3700) $PN EK26
J 0
(-2590 3710);
DISPLAY 0.680851 (-2590 3710);
PAINT MONO (-2590 3710);
FORCEPROP 0 LASTPIN (-2600 3350) $PN EU26
J 0
(-2590 3360);
DISPLAY 0.680851 (-2590 3360);
PAINT MONO (-2590 3360);
FORCEPROP 2 LAST PART_TYPE SMLF
J 0
(-3400 6275);
DISPLAY 0.680851 (-3400 6275);
FORCEPROP 1 LAST MATERIAL IC
J 0
(-3400 6025);
DISPLAY 0.723404 (-3400 6025);
PAINT GREEN (-3400 6025);
FORCEPROP 2 LAST VALUE PT5161LRS
J 0
(-3400 6225);
DISPLAY 0.680851 (-3400 6225);
FORCEPROP 2 LAST CDS_LIB pure_quanta
J 0
(-3050 4550);
DISPLAY INVISIBLE (-3050 4550);
FORCEPROP 1 LAST CDS_LMAN_SYM_OUTLINE -350,1450,300,-1400
J 0
(-3050 4550);
DISPLAY 0.468085 (-3050 4550);
PAINT GREEN (-3050 4550);
DISPLAY INVISIBLE (-3050 4550);
FORCEPROP 1 LAST NEEDS_NO_SIZE TRUE
J 0
(-3050 4550);
DISPLAY 0.723404 (-3050 4550);
PAINT GREEN (-3050 4550);
DISPLAY INVISIBLE (-3050 4550);
FORCEPROP 1 LAST PATH I38
J 0
(-3050 4550);
DISPLAY 0.723404 (-3050 4550);
PAINT GREEN (-3050 4550);
DISPLAY INVISIBLE (-3050 4550);
FORCEPROP 1 LAST PART_NUMBER AJ051610U03
J 0
(-3400 6100);
DISPLAY 0.723404 (-3400 6100);
PAINT GREEN (-3400 6100);
DISPLAY INVISIBLE (-3400 6100);
FORCEADD TAP..1
(-6550 3625);
FORCEPROP 3 LASTPIN (-6600 3625) SIG_NAME P5E_CPU1_P0_RX_DP<9>
J 0
(-6590 3635);
DISPLAY 0.659574 (-6590 3635);
PAINT MONO (-6590 3635);
DISPLAY INVISIBLE (-6590 3635);
FORCEPROP 1 LASTPIN (-6600 3625) BN 9
J 0
(-6612 3633);
DISPLAY 0.680851 (-6612 3633);
PAINT GREEN (-6612 3633);
FORCEPROP 2 LAST CDS_LIB standard
J 0
(-6550 3625);
DISPLAY INVISIBLE (-6550 3625);
FORCEPROP 1 LAST BODY_TYPE PLUMBING
J 0
(-6550 3675);
DISPLAY 0.872340 (-6550 3675);
PAINT GREEN (-6550 3675);
DISPLAY INVISIBLE (-6550 3675);
FORCEPROP 1 LAST HDL_TAP TRUE
J 0
(-6225 3500);
DISPLAY 0.872340 (-6225 3500);
DISPLAY INVISIBLE (-6225 3500);
FORCEPROP 1 LAST PATH I4
J 0
(-6552 3625);
DISPLAY 0.872340 (-6552 3625);
PAINT GREEN (-6552 3625);
DISPLAY INVISIBLE (-6552 3625);
FORCEADD TAP..1
(-6350 3525);
FORCEPROP 3 LASTPIN (-6400 3525) SIG_NAME P5E_CPU1_P0_RX_DN<9>
J 0
(-6390 3535);
DISPLAY 0.659574 (-6390 3535);
PAINT MONO (-6390 3535);
DISPLAY INVISIBLE (-6390 3535);
FORCEPROP 1 LASTPIN (-6400 3525) BN 9
J 0
(-6412 3533);
DISPLAY 0.680851 (-6412 3533);
PAINT GREEN (-6412 3533);
FORCEPROP 2 LAST CDS_LIB standard
J 0
(-6350 3525);
DISPLAY INVISIBLE (-6350 3525);
FORCEPROP 1 LAST BODY_TYPE PLUMBING
J 0
(-6350 3575);
DISPLAY 0.872340 (-6350 3575);
PAINT GREEN (-6350 3575);
DISPLAY INVISIBLE (-6350 3575);
FORCEPROP 1 LAST HDL_TAP TRUE
J 0
(-6025 3400);
DISPLAY 0.872340 (-6025 3400);
DISPLAY INVISIBLE (-6025 3400);
FORCEPROP 1 LAST PATH I5
J 0
(-6352 3525);
DISPLAY 0.872340 (-6352 3525);
PAINT GREEN (-6352 3525);
DISPLAY INVISIBLE (-6352 3525);
FORCEADD TAP..1
(-6350 3875);
FORCEPROP 3 LASTPIN (-6400 3875) SIG_NAME P5E_CPU1_P0_RX_DN<10>
J 0
(-6390 3885);
DISPLAY 0.659574 (-6390 3885);
PAINT MONO (-6390 3885);
DISPLAY INVISIBLE (-6390 3885);
FORCEPROP 1 LASTPIN (-6400 3875) BN 10
J 0
(-6412 3883);
DISPLAY 0.680851 (-6412 3883);
PAINT GREEN (-6412 3883);
FORCEPROP 2 LAST CDS_LIB standard
J 0
(-6350 3875);
DISPLAY INVISIBLE (-6350 3875);
FORCEPROP 1 LAST BODY_TYPE PLUMBING
J 0
(-6350 3925);
DISPLAY 0.872340 (-6350 3925);
PAINT GREEN (-6350 3925);
DISPLAY INVISIBLE (-6350 3925);
FORCEPROP 1 LAST HDL_TAP TRUE
J 0
(-6025 3750);
DISPLAY 0.872340 (-6025 3750);
DISPLAY INVISIBLE (-6025 3750);
FORCEPROP 1 LAST PATH I6
J 0
(-6352 3875);
DISPLAY 0.872340 (-6352 3875);
PAINT GREEN (-6352 3875);
DISPLAY INVISIBLE (-6352 3875);
FORCEADD TAP..1
(-6550 3975);
FORCEPROP 3 LASTPIN (-6600 3975) SIG_NAME P5E_CPU1_P0_RX_DP<10>
J 0
(-6590 3985);
DISPLAY 0.659574 (-6590 3985);
PAINT MONO (-6590 3985);
DISPLAY INVISIBLE (-6590 3985);
FORCEPROP 1 LASTPIN (-6600 3975) BN 10
J 0
(-6612 3983);
DISPLAY 0.680851 (-6612 3983);
PAINT GREEN (-6612 3983);
FORCEPROP 2 LAST CDS_LIB standard
J 0
(-6550 3975);
DISPLAY INVISIBLE (-6550 3975);
FORCEPROP 1 LAST BODY_TYPE PLUMBING
J 0
(-6550 4025);
DISPLAY 0.872340 (-6550 4025);
PAINT GREEN (-6550 4025);
DISPLAY INVISIBLE (-6550 4025);
FORCEPROP 1 LAST HDL_TAP TRUE
J 0
(-6225 3850);
DISPLAY 0.872340 (-6225 3850);
DISPLAY INVISIBLE (-6225 3850);
FORCEPROP 1 LAST PATH I7
J 0
(-6552 3975);
DISPLAY 0.872340 (-6552 3975);
PAINT GREEN (-6552 3975);
DISPLAY INVISIBLE (-6552 3975);
FORCEADD TAP..1
(-6550 4325);
FORCEPROP 3 LASTPIN (-6600 4325) SIG_NAME P5E_CPU1_P0_RX_DP<11>
J 0
(-6590 4335);
DISPLAY 0.659574 (-6590 4335);
PAINT MONO (-6590 4335);
DISPLAY INVISIBLE (-6590 4335);
FORCEPROP 1 LASTPIN (-6600 4325) BN 11
J 0
(-6612 4333);
DISPLAY 0.680851 (-6612 4333);
PAINT GREEN (-6612 4333);
FORCEPROP 2 LAST CDS_LIB standard
J 0
(-6550 4325);
DISPLAY INVISIBLE (-6550 4325);
FORCEPROP 1 LAST BODY_TYPE PLUMBING
J 0
(-6550 4375);
DISPLAY 0.872340 (-6550 4375);
PAINT GREEN (-6550 4375);
DISPLAY INVISIBLE (-6550 4375);
FORCEPROP 1 LAST HDL_TAP TRUE
J 0
(-6225 4200);
DISPLAY 0.872340 (-6225 4200);
DISPLAY INVISIBLE (-6225 4200);
FORCEPROP 1 LAST PATH I8
J 0
(-6552 4325);
DISPLAY 0.872340 (-6552 4325);
PAINT GREEN (-6552 4325);
DISPLAY INVISIBLE (-6552 4325);
FORCEADD TAP..1
(-6350 4225);
FORCEPROP 3 LASTPIN (-6400 4225) SIG_NAME P5E_CPU1_P0_RX_DN<11>
J 0
(-6390 4235);
DISPLAY 0.659574 (-6390 4235);
PAINT MONO (-6390 4235);
DISPLAY INVISIBLE (-6390 4235);
FORCEPROP 1 LASTPIN (-6400 4225) BN 11
J 0
(-6412 4233);
DISPLAY 0.680851 (-6412 4233);
PAINT GREEN (-6412 4233);
FORCEPROP 2 LAST CDS_LIB standard
J 0
(-6350 4225);
DISPLAY INVISIBLE (-6350 4225);
FORCEPROP 1 LAST BODY_TYPE PLUMBING
J 0
(-6350 4275);
DISPLAY 0.872340 (-6350 4275);
PAINT GREEN (-6350 4275);
DISPLAY INVISIBLE (-6350 4275);
FORCEPROP 1 LAST HDL_TAP TRUE
J 0
(-6025 4100);
DISPLAY 0.872340 (-6025 4100);
DISPLAY INVISIBLE (-6025 4100);
FORCEPROP 1 LAST PATH I9
J 0
(-6352 4225);
DISPLAY 0.872340 (-6352 4225);
PAINT GREEN (-6352 4225);
DISPLAY INVISIBLE (-6352 4225);
FORCEADD QUANTA_TITLE_BLOCK_C..1
(0 0);
FORCEPROP 0 LAST CDS_CON_LAST_MODIFIED Thu Sep 14 16:12:54 2023
J 0
(-1885 15);
DISPLAY INVISIBLE (-1885 15);
FORCEPROP 1 LAST CUSTOM_TXT_CDS <CON_LAST_MODIFIED>
J 0
(-1885 15);
DISPLAY 0.978723 (-1885 15);
FORCEPROP 2 LAST CUSTOM_TXT_CDS <XR_PAGE_TITLE>
J 0
(-7890 5250);
DISPLAY 0.638298 (-7890 5250);
PAINT PINK (-7890 5250);
DISPLAY INVISIBLE (-7890 5250);
FORCEPROP 1 LAST CUSTOM_TXT_CDS <NAME_2>
J 0
(-3175 50);
FORCEPROP 1 LAST CUSTOM_TXT_CDS <NAME_1>
J 0
(-3175 175);
FORCEPROP 1 LAST CUSTOM_TXT_CDS <Q_NUMBER>
J 0
(-1403 103);
DISPLAY 1.212766 (-1403 103);
FORCEPROP 1 LAST CUSTOM_TXT_CDS <Q_PROJ>
J 0
(-2382 102);
DISPLAY 1.212766 (-2382 102);
FORCEPROP 1 LAST CUSTOM_TXT_CDS <Q_REV>
J 0
(-184 103);
DISPLAY 1.212766 (-184 103);
FORCEPROP 1 LAST CUSTOM_TXT_CDS <CON_PAGE_NUM> OF <CON_TOTAL_PAGES>
J 0
(-446 18);
DISPLAY 0.978723 (-446 18);
FORCEPROP 1 LAST Q_TITLE RETIMER_CPU1_P0(2)
J 0
(-9366 26);
DISPLAY 2.446809 (-9366 26);
PAINT GREEN (-9366 26);
FORCEPROP 2 LAST PAGE_BORDER TRUE
J 0
(-7890 5250);
DISPLAY 0.638298 (-7890 5250);
PAINT PINK (-7890 5250);
DISPLAY INVISIBLE (-7890 5250);
FORCEPROP 1 LAST CDS_LMAN_SYM_OUTLINE -9475,6775,100,-125
J 0
(0 0);
DISPLAY 0.468085 (0 0);
PAINT GREEN (0 0);
DISPLAY INVISIBLE (0 0);
FORCEPROP 2 LAST CDS_LIB pure_quanta
J 0
(0 0);
DISPLAY INVISIBLE (0 0);
FORCEPROP 2 LAST CDS_XR_PAGE_TITLE CR-318 : @T6G_MB_LIB.T6G(SCH_1):PAGE318
J 0
(-7890 5250);
DISPLAY 0.638298 (-7890 5250);
PAINT PINK (-7890 5250);
DISPLAY INVISIBLE (-7890 5250);
FORCEPROP 1 LAST Q_DEPT BU9
J 1
(-3763 49);
DISPLAY 1.957447 (-3763 49);
PAINT GREEN (-3763 49);
DISPLAY INVISIBLE (-3763 49);
FORCEPROP 1 LAST COMMENT_BODY TRUE
J 0
(12 -13);
DISPLAY 0.978723 (12 -13);
PAINT GREEN (12 -13);
DISPLAY INVISIBLE (12 -13);
WIRE 17 -1 (-1975 5825)(-1975 5475);
WIRE 17 -1 (-1975 6025)(-1975 5825);
WIRE 17 -1 (-1975 5475)(-1975 5125);
WIRE 17 -1 (-1975 5125)(-1975 4775);
WIRE 17 -1 (-1975 6025)(-850 6025);
FORCEPROP 2 LAST SIG_NAME P5E_CPU1_P0_RX_DP<7:0>
J 0
(-1710 6035);
DISPLAY 0.680851 (-1710 6035);
PAINT WHITE (-1710 6035);
WIRE 17 -1 (-6500 4350)(-6500 4700);
WIRE 17 -1 (-6500 4350)(-6500 4000);
WIRE 17 -1 (-6500 5050)(-6500 4700);
WIRE 17 -1 (-6500 5400)(-6500 5050);
WIRE 17 -1 (-6500 4000)(-6500 3650);
WIRE 17 -1 (-6500 3650)(-6500 3300);
WIRE 17 -1 (-6500 5750)(-6500 5400);
WIRE 17 -1 (-6500 5825)(-6500 5750);
WIRE 17 -1 (-6500 5825)(-5375 5825);
FORCEPROP 2 LAST SIG_NAME P5E_CPU1_P0_RX_DP<15:8>
J 0
(-6235 5835);
DISPLAY 0.680851 (-6235 5835);
PAINT WHITE (-6235 5835);
WIRE 17 -1 (-1975 3725)(-1975 3375);
WIRE 17 -1 (-1975 4075)(-1975 3725);
WIRE 17 -1 (-1975 4425)(-1975 4075);
WIRE 17 -1 (-1975 4425)(-1975 4775);
WIRE 17 -1 (-6300 4250)(-6300 4600);
WIRE 17 -1 (-6300 4250)(-6300 3900);
WIRE 17 -1 (-6300 4950)(-6300 4600);
WIRE 17 -1 (-6300 5300)(-6300 4950);
WIRE 17 -1 (-6300 3900)(-6300 3550);
WIRE 17 -1 (-6300 3550)(-6300 3200);
WIRE 17 -1 (-6300 5650)(-6300 5300);
WIRE 17 -1 (-6300 5700)(-6300 5650);
WIRE 17 -1 (-6300 5700)(-5400 5700);
FORCEPROP 2 LAST SIG_NAME P5E_CPU1_P0_RX_DN<15:8>
J 0
(-6235 5710);
DISPLAY 0.680851 (-6235 5710);
PAINT WHITE (-6235 5710);
WIRE 17 -1 (-1775 5375)(-1775 5025);
WIRE 17 -1 (-1775 5725)(-1775 5375);
WIRE 17 -1 (-1775 5025)(-1775 4675);
WIRE 17 -1 (-1775 4325)(-1775 4675);
WIRE 17 -1 (-1775 5900)(-1775 5725);
WIRE 17 -1 (-1775 5900)(-875 5900);
FORCEPROP 2 LAST SIG_NAME P5E_CPU1_P0_RX_DN<7:0>
J 0
(-1710 5910);
DISPLAY 0.680851 (-1710 5910);
PAINT WHITE (-1710 5910);
WIRE 17 -1 (-1775 3625)(-1775 3275);
WIRE 17 -1 (-1775 3975)(-1775 3625);
WIRE 17 -1 (-1775 4325)(-1775 3975);
WIRE 16 -1 (-7125 5375)(-6600 5375);
WIRE 16 -1 (-7125 5275)(-6400 5275);
WIRE 16 -1 (-7125 5725)(-6600 5725);
WIRE 16 -1 (-7125 5625)(-6400 5625);
WIRE 16 -1 (-2600 3950)(-1875 3950);
WIRE 16 -1 (-2600 4050)(-2075 4050);
WIRE 16 -1 (-2600 3600)(-1875 3600);
WIRE 16 -1 (-2600 3700)(-2075 3700);
WIRE 16 -1 (-2600 4400)(-2075 4400);
WIRE 16 -1 (-2600 4300)(-1875 4300);
WIRE 16 -1 (-7125 4575)(-6400 4575);
WIRE 16 -1 (-2600 5700)(-1875 5700);
WIRE 16 -1 (-7125 3175)(-6400 3175);
WIRE 16 -1 (-7125 4925)(-6400 4925);
WIRE 16 -1 (-7125 3875)(-6400 3875);
WIRE 16 -1 (-7125 3525)(-6400 3525);
WIRE 16 -1 (-2600 5350)(-1875 5350);
WIRE 16 -1 (-2600 4650)(-1875 4650);
WIRE 16 -1 (-2600 3250)(-1875 3250);
WIRE 16 -1 (-2600 5000)(-1875 5000);
WIRE 16 -1 (-7125 4225)(-6400 4225);
WIRE 16 -1 (-7125 3625)(-6600 3625);
WIRE 16 -1 (-7125 5025)(-6600 5025);
WIRE 16 -1 (-7125 4675)(-6600 4675);
WIRE 16 -1 (-7125 3975)(-6600 3975);
WIRE 16 -1 (-7125 3275)(-6600 3275);
WIRE 16 -1 (-2600 5800)(-2075 5800);
WIRE 16 -1 (-2600 4750)(-2075 4750);
WIRE 16 -1 (-2600 5100)(-2075 5100);
WIRE 16 -1 (-2600 3350)(-2075 3350);
WIRE 16 -1 (-7125 4325)(-6600 4325);
WIRE 16 -1 (-2600 5450)(-2075 5450);
FORCENOTE
RETIMER TO CPU
(-7925 2700) 0;
DISPLAY LEFT (-7925 2700);
DISPLAY 3.148936 (-7925 2700);
FORCENOTE
RETIMER TO CPU
(-3425 2800) 0;
DISPLAY LEFT (-3425 2800);
DISPLAY 3.148936 (-3425 2800);
FORCENOTE
P5E_CPU1_P0_RX_DP/DN<0-15> LANE REVERSAL
(-9025 6375) 0;
DISPLAY LEFT (-9025 6375);
DISPLAY 2.000000 (-9025 6375);
QUIT
